# T6G (Grand Teton) — schematic netlist excerpt (pin names and nets, part order shuffled) for the footprints in the layout excerpt that follows; sources: Cadence DE-HDL packaged netlist, KiCad conversion of 04192023_DAF0TMB3IC0_F0TG_MB_C_brd_V02_OCP.brd

R204  Q_RES  0 5% CHIP  pkg 0402LF  page 82 : A = CPU1_XTRIG_L4 ; B = FM_CPU1_XTRIG_L4
PC501_2  Q_CAP  22UF 4V 20% X6S  pkg C0805  page 194 : A = PVDDCR_CPU0_P0 ; B = GND
C1129  Q_CAP  0.1UF 16V 10% X7R  pkg C0402  page 83 : A = P1V8_AUX ; B = GND

(kicad_pcb
	(version 20260206)
	(generator "pcbnew")
	(generator_version "10.0")
	(general
		(thickness 1.6)
		(legacy_teardrops no)
	)
	(paper "A4")
	(title_block
		(title "04192023_DAF0TMB3IC0_F0TG_MB_C_brd_V02_OCP.brd")
		(comment 1 "Grand Teton / footprints 7959-7961 of 8354")
	)
	(layers
		(0 "F.Cu" signal "TOP")
		(4 "In1.Cu" signal "GND")
		(6 "In2.Cu" signal "IN1")
		(8 "In3.Cu" signal "GND1")
		(10 "In4.Cu" signal "IN2")
		(12 "In5.Cu" signal "GND2")
		(14 "In6.Cu" signal "IN3")
		(16 "In7.Cu" signal "GND3")
		(18 "In8.Cu" signal "VCC")
		(20 "In9.Cu" signal "VCC1")
		(22 "In10.Cu" signal "GND4")
		(24 "In11.Cu" signal "IN4")
		(26 "In12.Cu" signal "GND5")
		(28 "In13.Cu" signal "IN5")
		(30 "In14.Cu" signal "GND6")
		(32 "In15.Cu" signal "IN6")
		(34 "In16.Cu" signal "GND7")
		(2 "B.Cu" signal "BOTTOM")
		(9 "F.Adhes" user "F.Adhesive")
		(11 "B.Adhes" user "B.Adhesive")
		(13 "F.Paste" user "Package Geometry/Pastemask Top")
		(15 "B.Paste" user "Package Geometry/Pastemask Bottom")
		(5 "F.SilkS" user "Ref Des/Silkscreen Top")
		(7 "B.SilkS" user "Ref Des/Silkscreen Bottom")
		(1 "F.Mask" user "Board Geometry/Soldermask Top")
		(3 "B.Mask" user "Board Geometry/Soldermask Bottom")
		(17 "Dwgs.User" user "User.Drawings")
		(19 "Cmts.User" user "User.Comments")
		(21 "Eco1.User" user "User.Eco1")
		(23 "Eco2.User" user "User.Eco2")
		(25 "Edge.Cuts" user "Board Geometry/Outline")
		(27 "Margin" user)
		(31 "F.CrtYd" user "Package Geometry/Place Bound Top")
		(29 "B.CrtYd" user "Package Geometry/Place Bound Bottom")
		(35 "F.Fab" user "Ref Des/Assembly Top")
		(33 "B.Fab" user "Ref Des/Assembly Bottom")
	)
	(footprint ""
		(layer "B.Cu")
		(at 175.641 -100.294948 -90)
		(property "Reference" "R204"
			(at 0 0 90)
			(layer "B.SilkS")
			(hide yes)
			(effects
				(font
					(size 1.27 1.27)
				)
				(justify mirror)
			)
		)
		(property "Value" ""
			(at 0 0 90)
			(layer "B.Fab")
			(effects
				(font
					(size 1.27 1.27)
				)
				(justify mirror)
			)
		)
		(duplicate_pad_numbers_are_jumpers no)
		(fp_line
			(start -0.7874 0.4064)
			(end 0.7874 0.4064)
			(stroke
				(width 0.1524)
				(type default)
			)
			(layer "B.SilkS")
		)
		(fp_line
			(start 0.7874 0.4064)
			(end 0.7874 -0.4064)
			(stroke
				(width 0.1524)
				(type default)
			)
			(layer "B.SilkS")
		)
		(fp_line
			(start -0.7874 -0.4064)
			(end -0.7874 0.4064)
			(stroke
				(width 0.1524)
				(type default)
			)
			(layer "B.SilkS")
		)
		(fp_line
			(start 0.7874 -0.4064)
			(end -0.7874 -0.4064)
			(stroke
				(width 0.1524)
				(type default)
			)
			(layer "B.SilkS")
		)
		(fp_line
			(start -0.67945 0.3048)
			(end -0.120396 0.3048)
			(stroke
				(width 0.1)
				(type default)
			)
			(layer "B.Fab")
		)
		(fp_line
			(start -0.120396 0.3048)
			(end -0.120396 0.2794)
			(stroke
				(width 0.1)
				(type default)
			)
			(layer "B.Fab")
		)
		(fp_line
			(start 0.12065 0.3048)
			(end 0.67945 0.3048)
			(stroke
				(width 0.1)
				(type default)
			)
			(layer "B.Fab")
		)
		(fp_line
			(start 0.67945 0.3048)
			(end 0.67945 -0.305054)
			(stroke
				(width 0.1)
				(type default)
			)
			(layer "B.Fab")
		)
		(fp_line
			(start -0.120396 0.2794)
			(end 0.12065 0.2794)
			(stroke
				(width 0.1)
				(type default)
			)
			(layer "B.Fab")
		)
		(fp_line
			(start 0.12065 0.2794)
			(end 0.12065 0.3048)
			(stroke
				(width 0.1)
				(type default)
			)
			(layer "B.Fab")
		)
		(fp_line
			(start -0.12065 -0.2794)
			(end -0.12065 -0.3048)
			(stroke
				(width 0.1)
				(type default)
			)
			(layer "B.Fab")
		)
		(fp_line
			(start 0.12065 -0.2794)
			(end -0.12065 -0.2794)
			(stroke
				(width 0.1)
				(type default)
			)
			(layer "B.Fab")
		)
		(fp_line
			(start -0.67945 -0.3048)
			(end -0.67945 0.3048)
			(stroke
				(width 0.1)
				(type default)
			)
			(layer "B.Fab")
		)
		(fp_line
			(start -0.12065 -0.3048)
			(end -0.67945 -0.3048)
			(stroke
				(width 0.1)
				(type default)
			)
			(layer "B.Fab")
		)
		(fp_line
			(start 0.12065 -0.305054)
			(end 0.12065 -0.2794)
			(stroke
				(width 0.1)
				(type default)
			)
			(layer "B.Fab")
		)
		(fp_line
			(start 0.67945 -0.305054)
			(end 0.12065 -0.305054)
			(stroke
				(width 0.1)
				(type default)
			)
			(layer "B.Fab")
		)
		(pad "1" smd circle
			(at 0.40005 0 90)
			(size 0 0)
			(layers "B.Cu" "B.Mask" "B.Paste")
			(net "CPU1_XTRIG_L4")
		)
		(pad "2" smd circle
			(at -0.40005 0 90)
			(size 0 0)
			(layers "B.Cu" "B.Mask" "B.Paste")
			(net "FM_CPU1_XTRIG_L4")
		)
	)
	(footprint ""
		(layer "B.Cu")
		(at 368.892836 -191.32423 90)
		(property "Reference" "PC501_2"
			(at 0 0 90)
			(layer "B.SilkS")
			(hide yes)
			(effects
				(font
					(size 1.27 1.27)
				)
				(justify mirror)
			)
		)
		(property "Value" ""
			(at 0 0 90)
			(layer "B.Fab")
			(effects
				(font
					(size 1.27 1.27)
				)
				(justify mirror)
			)
		)
		(duplicate_pad_numbers_are_jumpers no)
		(fp_line
			(start 1.524 -0.762)
			(end -1.524 -0.762)
			(stroke
				(width 0.1524)
				(type default)
			)
			(layer "B.SilkS")
		)
		(fp_line
			(start -1.524 -0.762)
			(end -1.524 0.762)
			(stroke
				(width 0.1524)
				(type default)
			)
			(layer "B.SilkS")
		)
		(fp_line
			(start 1.524 0.762)
			(end 1.524 -0.762)
			(stroke
				(width 0.1524)
				(type default)
			)
			(layer "B.SilkS")
		)
		(fp_line
			(start -1.524 0.762)
			(end 1.524 0.762)
			(stroke
				(width 0.1524)
				(type default)
			)
			(layer "B.SilkS")
		)
		(fp_line
			(start 1.1049 -0.724916)
			(end 1.1049 0.724916)
			(stroke
				(width 0.1)
				(type default)
			)
			(layer "B.Fab")
		)
		(fp_line
			(start -1.1049 -0.724916)
			(end 1.1049 -0.724916)
			(stroke
				(width 0.1)
				(type default)
			)
			(layer "B.Fab")
		)
		(fp_line
			(start 1.1049 0.724916)
			(end -1.1049 0.724916)
			(stroke
				(width 0.1)
				(type default)
			)
			(layer "B.Fab")
		)
		(fp_line
			(start -1.1049 0.724916)
			(end -1.1049 -0.724916)
			(stroke
				(width 0.1)
				(type default)
			)
			(layer "B.Fab")
		)
		(pad "1" smd rect
			(at 0.889 0 90)
			(size 1.016 1.27)
			(layers "B.Cu" "B.Mask" "B.Paste")
			(net "PVDDCR_CPU0_P0")
		)
		(pad "2" smd rect
			(at -0.889 0 90)
			(size 1.016 1.27)
			(layers "B.Cu" "B.Mask" "B.Paste")
			(net "GND")
		)
	)
	(footprint ""
		(layer "B.Cu")
		(at 183.132476 -117.842792)
		(property "Reference" "C1129"
			(at 0 0 0)
			(layer "B.SilkS")
			(hide yes)
			(effects
				(font
					(size 1.27 1.27)
				)
				(justify mirror)
			)
		)
		(property "Value" ""
			(at 0 0 0)
			(layer "B.Fab")
			(effects
				(font
					(size 1.27 1.27)
				)
				(justify mirror)
			)
		)
		(duplicate_pad_numbers_are_jumpers no)
		(fp_line
			(start -0.69215 -0.2921)
			(end -0.69215 0.2921)
			(stroke
				(width 0.1524)
				(type default)
			)
			(layer "B.SilkS")
		)
		(fp_line
			(start -0.69215 0.2921)
			(end 0.69215 0.2921)
			(stroke
				(width 0.1524)
				(type default)
			)
			(layer "B.SilkS")
		)
		(fp_line
			(start 0.69215 -0.2921)
			(end -0.69215 -0.2921)
			(stroke
				(width 0.1524)
				(type default)
			)
			(layer "B.SilkS")
		)
		(fp_line
			(start 0.69215 0.2921)
			(end 0.69215 -0.2921)
			(stroke
				(width 0.1524)
				(type default)
			)
			(layer "B.SilkS")
		)
		(fp_line
			(start -0.51435 -0.2794)
			(end -0.51435 0.2794)
			(stroke
				(width 0.1)
				(type default)
			)
			(layer "B.Fab")
		)
		(fp_line
			(start -0.51435 0.2794)
			(end 0.51435 0.2794)
			(stroke
				(width 0.1)
				(type default)
			)
			(layer "B.Fab")
		)
		(fp_line
			(start 0.51435 -0.2794)
			(end -0.51435 -0.2794)
			(stroke
				(width 0.1)
				(type default)
			)
			(layer "B.Fab")
		)
		(fp_line
			(start 0.51435 0.2794)
			(end 0.51435 -0.2794)
			(stroke
				(width 0.1)
				(type default)
			)
			(layer "B.Fab")
		)
		(pad "1" smd circle
			(at 0.40005 0 180)
			(size 0 0)
			(layers "B.Cu" "B.Mask" "B.Paste")
			(net "P1V8_AUX")
		)
		(pad "2" smd circle
			(at -0.40005 0 180)
			(size 0 0)
			(layers "B.Cu" "B.Mask" "B.Paste")
			(net "GND")
		)
		(zone
			(layer "B.Cu")
			(hatch none 0.5)
			(connect_pads
				(clearance 0)
			)
			(min_thickness 0.25)
			(keepout
				(tracks not_allowed)
				(vias allowed)
				(pads allowed)
				(copperpour not_allowed)
				(footprints allowed)
			)
			(placement
				(enabled no)
				(sheetname "")
			)
			(fill
				(thermal_gap 0.5)
				(thermal_bridge_width 0.5)
				(island_removal_mode 0)
			)
			(polygon
				(pts
					(xy 182.941976 -117.755162) (xy 182.941976 -117.930422) (xy 183.032146 -117.988842) (xy 183.231536 -117.988842)
					(xy 183.322976 -117.930676) (xy 183.322976 -117.755162) (xy 183.231536 -117.696996) (xy 183.032146 -117.696996)
				)
			)
		)
	)
)
